# SCM (Grand Teton) — schematic netlist excerpt (pin names and nets, part order shuffled) for the footprints in the layout excerpt that follows; sources: Cadence DE-HDL packaged netlist, KiCad conversion of 12092022_DA0F0TMDCD0_F0T_Management_Board_D_brd_V3_OCP.brd

C203  Q_CAP  0.1UF 25V 10% X7R  pkg 0402  page 23 : A = P5V_AUX ; B = GND
C176  Q_CAP  1UF 25V 10% X6S  pkg C0402  page 41 : A = PVCCA_AUX_PLD ; B = GND

(kicad_pcb
	(version 20260206)
	(generator "pcbnew")
	(generator_version "10.0")
	(general
		(thickness 1.6)
		(legacy_teardrops no)
	)
	(paper "A4")
	(title_block
		(title "12092022_DA0F0TMDCD0_F0T_Management_Board_D_brd_V3_OCP.brd")
		(comment 1 "Grand Teton / footprints 751-752 of 1440")
	)
	(layers
		(0 "F.Cu" signal "TOP")
		(4 "In1.Cu" signal "GND")
		(6 "In2.Cu" signal "IN1")
		(8 "In3.Cu" signal "GND1")
		(10 "In4.Cu" signal "IN2")
		(12 "In5.Cu" signal "VCC")
		(14 "In6.Cu" signal "VCC1")
		(16 "In7.Cu" signal "IN3")
		(18 "In8.Cu" signal "GND2")
		(20 "In9.Cu" signal "IN4")
		(22 "In10.Cu" signal "GND3")
		(2 "B.Cu" signal "BOTTOM")
		(9 "F.Adhes" user "F.Adhesive")
		(11 "B.Adhes" user "B.Adhesive")
		(13 "F.Paste" user "Package Geometry/Pastemask Top")
		(15 "B.Paste" user "Package Geometry/Pastemask Bottom")
		(5 "F.SilkS" user "Ref Des/Silkscreen Top")
		(7 "B.SilkS" user "Ref Des/Silkscreen Bottom")
		(1 "F.Mask" user "Board Geometry/Soldermask Top")
		(3 "B.Mask" user "Board Geometry/Soldermask Bottom")
		(17 "Dwgs.User" user "User.Drawings")
		(19 "Cmts.User" user "User.Comments")
		(21 "Eco1.User" user "User.Eco1")
		(23 "Eco2.User" user "User.Eco2")
		(25 "Edge.Cuts" user "Board Geometry/Outline")
		(27 "Margin" user)
		(31 "F.CrtYd" user "Package Geometry/Place Bound Top")
		(29 "B.CrtYd" user "Package Geometry/Place Bound Bottom")
		(35 "F.Fab" user "Ref Des/Assembly Top")
		(33 "B.Fab" user "Ref Des/Assembly Bottom")
	)
	(footprint ""
		(layer "B.Cu")
		(at 20.282408 -92.8116 -90)
		(property "Reference" "C176"
			(at 0 0 90)
			(layer "B.SilkS")
			(hide yes)
			(effects
				(font
					(size 1.27 1.27)
				)
				(justify mirror)
			)
		)
		(property "Value" ""
			(at 0 0 90)
			(layer "B.Fab")
			(effects
				(font
					(size 1.27 1.27)
				)
				(justify mirror)
			)
		)
		(duplicate_pad_numbers_are_jumpers no)
		(fp_line
			(start -0.69215 0.2921)
			(end 0.69215 0.2921)
			(stroke
				(width 0.1524)
				(type default)
			)
			(layer "B.SilkS")
		)
		(fp_line
			(start 0.69215 0.2921)
			(end 0.69215 -0.2921)
			(stroke
				(width 0.1524)
				(type default)
			)
			(layer "B.SilkS")
		)
		(fp_line
			(start -0.69215 -0.2921)
			(end -0.69215 0.2921)
			(stroke
				(width 0.1524)
				(type default)
			)
			(layer "B.SilkS")
		)
		(fp_line
			(start 0.69215 -0.2921)
			(end -0.69215 -0.2921)
			(stroke
				(width 0.1524)
				(type default)
			)
			(layer "B.SilkS")
		)
		(fp_line
			(start -0.51435 0.2794)
			(end 0.51435 0.2794)
			(stroke
				(width 0.1)
				(type default)
			)
			(layer "B.Fab")
		)
		(fp_line
			(start 0.51435 0.2794)
			(end 0.51435 -0.2794)
			(stroke
				(width 0.1)
				(type default)
			)
			(layer "B.Fab")
		)
		(fp_line
			(start -0.51435 -0.2794)
			(end -0.51435 0.2794)
			(stroke
				(width 0.1)
				(type default)
			)
			(layer "B.Fab")
		)
		(fp_line
			(start 0.51435 -0.2794)
			(end -0.51435 -0.2794)
			(stroke
				(width 0.1)
				(type default)
			)
			(layer "B.Fab")
		)
		(pad "1" smd circle
			(at 0.40005 0 90)
			(size 0 0)
			(layers "B.Cu" "B.Mask" "B.Paste")
			(net "PVCCA_AUX_PLD")
		)
		(pad "2" smd circle
			(at -0.40005 0 90)
			(size 0 0)
			(layers "B.Cu" "B.Mask" "B.Paste")
			(net "GND")
		)
		(zone
			(layer "B.Cu")
			(hatch none 0.5)
			(connect_pads
				(clearance 0)
			)
			(min_thickness 0.25)
			(keepout
				(tracks not_allowed)
				(vias allowed)
				(pads allowed)
				(copperpour not_allowed)
				(footprints allowed)
			)
			(placement
				(enabled no)
				(sheetname "")
			)
			(fill
				(thermal_gap 0.5)
				(thermal_bridge_width 0.5)
				(island_removal_mode 0)
			)
			(polygon
				(pts
					(xy 20.194778 -92.6211) (xy 20.136612 -92.71254) (xy 20.136612 -92.91193) (xy 20.194778 -93.0021)
					(xy 20.370038 -93.0021) (xy 20.428458 -92.91193) (xy 20.428458 -92.71254) (xy 20.370292 -92.6211)
				)
			)
		)
	)
	(footprint ""
		(layer "B.Cu")
		(at 31.623 -41.4147 -90)
		(property "Reference" "C203"
			(at 0 0 90)
			(layer "B.SilkS")
			(hide yes)
			(effects
				(font
					(size 1.27 1.27)
				)
				(justify mirror)
			)
		)
		(property "Value" ""
			(at 0 0 90)
			(layer "B.Fab")
			(effects
				(font
					(size 1.27 1.27)
				)
				(justify mirror)
			)
		)
		(duplicate_pad_numbers_are_jumpers no)
		(fp_line
			(start -0.7874 0.4064)
			(end 0.7874 0.4064)
			(stroke
				(width 0.1524)
				(type default)
			)
			(layer "B.SilkS")
		)
		(fp_line
			(start 0.7874 0.4064)
			(end 0.7874 -0.4064)
			(stroke
				(width 0.1524)
				(type default)
			)
			(layer "B.SilkS")
		)
		(fp_line
			(start -0.7874 -0.4064)
			(end -0.7874 0.4064)
			(stroke
				(width 0.1524)
				(type default)
			)
			(layer "B.SilkS")
		)
		(fp_line
			(start 0.7874 -0.4064)
			(end -0.7874 -0.4064)
			(stroke
				(width 0.1524)
				(type default)
			)
			(layer "B.SilkS")
		)
		(fp_line
			(start -0.67945 0.3048)
			(end -0.120396 0.3048)
			(stroke
				(width 0.1)
				(type default)
			)
			(layer "B.Fab")
		)
		(fp_line
			(start -0.120396 0.3048)
			(end -0.120396 0.2794)
			(stroke
				(width 0.1)
				(type default)
			)
			(layer "B.Fab")
		)
		(fp_line
			(start 0.12065 0.3048)
			(end 0.67945 0.3048)
			(stroke
				(width 0.1)
				(type default)
			)
			(layer "B.Fab")
		)
		(fp_line
			(start 0.67945 0.3048)
			(end 0.67945 -0.305054)
			(stroke
				(width 0.1)
				(type default)
			)
			(layer "B.Fab")
		)
		(fp_line
			(start -0.120396 0.2794)
			(end 0.12065 0.2794)
			(stroke
				(width 0.1)
				(type default)
			)
			(layer "B.Fab")
		)
		(fp_line
			(start 0.12065 0.2794)
			(end 0.12065 0.3048)
			(stroke
				(width 0.1)
				(type default)
			)
			(layer "B.Fab")
		)
		(fp_line
			(start -0.12065 -0.2794)
			(end -0.12065 -0.3048)
			(stroke
				(width 0.1)
				(type default)
			)
			(layer "B.Fab")
		)
		(fp_line
			(start 0.12065 -0.2794)
			(end -0.12065 -0.2794)
			(stroke
				(width 0.1)
				(type default)
			)
			(layer "B.Fab")
		)
		(fp_line
			(start -0.67945 -0.3048)
			(end -0.67945 0.3048)
			(stroke
				(width 0.1)
				(type default)
			)
			(layer "B.Fab")
		)
		(fp_line
			(start -0.12065 -0.3048)
			(end -0.67945 -0.3048)
			(stroke
				(width 0.1)
				(type default)
			)
			(layer "B.Fab")
		)
		(fp_line
			(start 0.12065 -0.305054)
			(end 0.12065 -0.2794)
			(stroke
				(width 0.1)
				(type default)
			)
			(layer "B.Fab")
		)
		(fp_line
			(start 0.67945 -0.305054)
			(end 0.12065 -0.305054)
			(stroke
				(width 0.1)
				(type default)
			)
			(layer "B.Fab")
		)
		(pad "1" smd circle
			(at 0.40005 0 90)
			(size 0 0)
			(layers "B.Cu" "B.Mask" "B.Paste")
			(net "P5V_AUX")
		)
		(pad "2" smd circle
			(at -0.40005 0 90)
			(size 0 0)
			(layers "B.Cu" "B.Mask" "B.Paste")
			(net "GND")
		)
	)
)
